(kicad_pcb
	(version 20240108)
	(generator "pcbnew")
	(generator_version "8.0")
	(general
		(thickness 1.62)
		(legacy_teardrops no)
	)
	(paper "A4")
	(title_block
		(title "Jetson Orin Baseboard")
		(date "2025-03-12")
		(rev "1.3.4")
		(company "Antmicro Ltd")
		(comment 1 "www.antmicro.com")
		(comment 9 "footprints 222-226 of 677")
	)
	(layers
		(0 "F.Cu" signal)
		(1 "In1.Cu" signal)
		(2 "In2.Cu" signal)
		(3 "In3.Cu" signal)
		(4 "In4.Cu" jumper)
		(5 "In5.Cu" signal)
		(6 "In6.Cu" signal)
		(31 "B.Cu" signal)
		(32 "B.Adhes" user "B.Adhesive")
		(33 "F.Adhes" user "F.Adhesive")
		(34 "B.Paste" user)
		(35 "F.Paste" user)
		(36 "B.SilkS" user "B.Silkscreen")
		(37 "F.SilkS" user "F.Silkscreen")
		(38 "B.Mask" user)
		(39 "F.Mask" user)
		(40 "Dwgs.User" user "User.Drawings")
		(41 "Cmts.User" user "User.Comments")
		(42 "Eco1.User" user "User.Eco1")
		(43 "Eco2.User" user "User.Eco2")
		(44 "Edge.Cuts" user)
		(45 "Margin" user)
		(46 "B.CrtYd" user "B.Courtyard")
		(47 "F.CrtYd" user "F.Courtyard")
		(48 "B.Fab" user)
		(49 "F.Fab" user)
	)
	(footprint "antmicro-footprints:TSOT23-6"
		(layer "F.Cu")
		(at 63 110.05 90)
		(property "Reference" "U9"
			(at -1.9 -1.89 90)
			(layer "F.SilkS")
			(effects
				(font
					(size 0.7 0.7)
					(thickness 0.15)
				)
				(justify left bottom)
			)
		)
		(property "Value" "AP22615A_TSOT26"
			(at 0 2.6 90)
			(layer "F.Fab")
			(effects
				(font
					(size 0.7 0.7)
					(thickness 0.15)
				)
				(justify left bottom)
			)
		)
		(property "Footprint" "antmicro-footprints:TSOT23-6"
			(at 0 0 90)
			(layer "F.Fab")
			(hide yes)
			(effects
				(font
					(size 1.27 1.27)
					(thickness 0.15)
				)
			)
		)
		(property "Datasheet" "https://www.mouser.com/datasheet/2/115/DIOD_S_A0008958405_1-2543193.pdf"
			(at 0 0 90)
			(layer "F.Fab")
			(hide yes)
			(effects
				(font
					(size 1.27 1.27)
					(thickness 0.15)
				)
			)
		)
		(property "Author" "Antmicro"
			(at 173.05 47.05 0)
			(layer "F.Fab")
			(hide yes)
			(effects
				(font
					(size 1 1)
					(thickness 0.15)
				)
			)
		)
		(property "License" "Apache-2.0"
			(at 173.05 47.05 0)
			(layer "F.Fab")
			(hide yes)
			(effects
				(font
					(size 1 1)
					(thickness 0.15)
				)
			)
		)
		(property "MPN" "AP22615AWU-7"
			(at 173.05 47.05 0)
			(layer "F.Fab")
			(hide yes)
			(effects
				(font
					(size 1 1)
					(thickness 0.15)
				)
			)
		)
		(property "Manufacturer" "Diodes Incorporated"
			(at 173.05 47.05 0)
			(layer "F.Fab")
			(hide yes)
			(effects
				(font
					(size 1 1)
					(thickness 0.15)
				)
			)
		)
		(sheetname "USB Debug, DP")
		(sheetfile "usb.kicad_sch")
		(attr smd)
		(fp_line
			(start -1 -1.5)
			(end -1 -1.375)
			(stroke
				(width 0.15)
				(type solid)
			)
			(layer "F.SilkS")
		)
		(fp_line
			(start 1 -1.497)
			(end -1 -1.5)
			(stroke
				(width 0.15)
				(type solid)
			)
			(layer "F.SilkS")
		)
		(fp_line
			(start 1 -1.497)
			(end 1 -1.375)
			(stroke
				(width 0.15)
				(type solid)
			)
			(layer "F.SilkS")
		)
		(fp_line
			(start 1 1.55)
			(end 1 1.4)
			(stroke
				(width 0.15)
				(type solid)
			)
			(layer "F.SilkS")
		)
		(fp_line
			(start 1 1.55)
			(end -1 1.55)
			(stroke
				(width 0.15)
				(type solid)
			)
			(layer "F.SilkS")
		)
		(fp_line
			(start -1 1.55)
			(end -1 1.4)
			(stroke
				(width 0.15)
				(type solid)
			)
			(layer "F.SilkS")
		)
		(fp_circle
			(center -1.44 -1.5)
			(end -1.39 -1.5)
			(stroke
				(width 0.15)
				(type solid)
			)
			(fill solid)
			(layer "F.SilkS")
		)
		(fp_rect
			(start 1.93 -1.7)
			(end -1.93 1.7)
			(stroke
				(width 0.05)
				(type solid)
			)
			(fill none)
			(layer "F.CrtYd")
		)
		(fp_line
			(start -0.45 -1.521)
			(end -0.876 -1.096)
			(stroke
				(width 0.15)
				(type solid)
			)
			(layer "F.Fab")
		)
		(fp_rect
			(start 0.875 1.528)
			(end -0.875 -1.525)
			(stroke
				(width 0.15)
				(type solid)
			)
			(fill none)
			(layer "F.Fab")
		)
		(fp_text user "${REFERENCE}"
			(at -1.93 3.8 90)
			(layer "F.Fab")
			(hide yes)
			(effects
				(font
					(size 0.7 0.7)
					(thickness 0.15)
				)
				(justify left bottom)
			)
		)
		(fp_text user "License: Apache-2.0"
			(at -1.93 6.199 90)
			(layer "F.Fab")
			(hide yes)
			(effects
				(font
					(size 0.7 0.7)
					(thickness 0.15)
				)
				(justify left bottom)
			)
		)
		(fp_text user "Author: Antmicro"
			(at -1.93 5 90)
			(layer "F.Fab")
			(hide yes)
			(effects
				(font
					(size 0.7 0.7)
					(thickness 0.15)
				)
				(justify left bottom)
			)
		)
		(pad "1" smd rect
			(at -1.301 -0.947)
			(size 0.7 1.2)
			(layers "F.Cu" "F.Paste" "F.Mask")
			(net 196 "/USB Debug, DP/USBC3_VBUS")
			(pinfunction "OUT")
			(pintype "power_out")
		)
		(pad "2" smd rect
			(at -1.301 0.004)
			(size 0.7 1.2)
			(layers "F.Cu" "F.Paste" "F.Mask")
			(net 1 "GND")
			(pinfunction "GND")
			(pintype "power_in")
		)
		(pad "3" smd rect
			(at -1.301 0.954)
			(size 0.7 1.2)
			(layers "F.Cu" "F.Paste" "F.Mask")
			(net 501 "/USB Debug, DP/USBC3_FLG")
			(pinfunction "FLG")
			(pintype "output")
		)
		(pad "4" smd rect
			(at 1.299 0.954)
			(size 0.7 1.2)
			(layers "F.Cu" "F.Paste" "F.Mask")
			(net 657 "Net-(U9-EN)")
			(pinfunction "EN")
			(pintype "input")
		)
		(pad "5" smd rect
			(at 1.299 0.004)
			(size 0.7 1.2)
			(layers "F.Cu" "F.Paste" "F.Mask")
			(net 672 "Net-(U9-ISET)")
			(pinfunction "ISET")
			(pintype "passive")
		)
		(pad "6" smd rect
			(at 1.299 -0.947)
			(size 0.7 1.2)
			(layers "F.Cu" "F.Paste" "F.Mask")
			(net 99 "+5V")
			(pinfunction "IN")
			(pintype "power_in")
		)
	)
	(footprint "antmicro-footprints:Fiducial_1mm_Mask2mm"
		(layer "F.Cu")
		(at 148.6 69.9)
		(descr "Circular Fiducial, 1mm bare copper, 3mm soldermask opening")
		(tags "fiducial")
		(property "Reference" "FID3"
			(at 0 -1.4 0)
			(layer "F.SilkS")
			(hide yes)
			(effects
				(font
					(size 0.7 0.7)
					(thickness 0.15)
				)
				(justify left bottom)
			)
		)
		(property "Value" "Fiducial_1mm_Mask2mm"
			(at 0 2.2 0)
			(layer "F.Fab")
			(effects
				(font
					(size 0.7 0.7)
					(thickness 0.15)
				)
				(justify left bottom)
			)
		)
		(property "Footprint" "antmicro-footprints:Fiducial_1mm_Mask2mm"
			(at 0 0 0)
			(layer "F.Fab")
			(hide yes)
			(effects
				(font
					(size 1.27 1.27)
					(thickness 0.15)
				)
			)
		)
		(attr board_only exclude_from_pos_files exclude_from_bom)
		(fp_circle
			(center 0 0)
			(end 1.24 0)
			(stroke
				(width 0.05)
				(type solid)
			)
			(fill none)
			(layer "F.CrtYd")
		)
		(fp_circle
			(center 0 0)
			(end 0.999 0)
			(stroke
				(width 0.15)
				(type solid)
			)
			(fill none)
			(layer "F.Fab")
		)
		(fp_text user "License: Apache-2.0"
			(at -1.25 7.003 0)
			(layer "F.Fab")
			(hide yes)
			(effects
				(font
					(size 0.7 0.7)
					(thickness 0.15)
				)
				(justify left bottom)
			)
		)
		(fp_text user "Author: Antmicro"
			(at -1.25 5.803 0)
			(layer "F.Fab")
			(hide yes)
			(effects
				(font
					(size 0.7 0.7)
					(thickness 0.15)
				)
				(justify left bottom)
			)
		)
		(fp_text user "${REFERENCE}"
			(at -1.25 4.603 0)
			(layer "F.Fab")
			(hide yes)
			(effects
				(font
					(size 0.7 0.7)
					(thickness 0.15)
				)
				(justify left bottom)
			)
		)
		(pad "" smd circle
			(at 0 0)
			(size 1 1)
			(layers "F.Cu" "F.Mask")
			(solder_mask_margin 0.5)
			(clearance 0.5)
		)
	)
	(footprint "antmicro-footprints:C_0603_1608Metric_EIA"
		(layer "F.Cu")
		(at 73.89 91.67 -90)
		(descr "Capacitor SMD 0603, IPC-7351 Density Level A")
		(tags "Capacitor 0603")
		(property "Reference" "C154"
			(at -6.406396 -13.78 -90)
			(layer "F.SilkS")
			(effects
				(font
					(size 0.7 0.7)
					(thickness 0.15)
				)
				(justify left bottom)
			)
		)
		(property "Value" "C_22u_16V_0603"
			(at -1.42757 1.770288 -90)
			(layer "F.Fab")
			(effects
				(font
					(size 0.7 0.7)
					(thickness 0.15)
				)
				(justify left bottom)
			)
		)
		(property "Footprint" "antmicro-footprints:C_0603_1608Metric_EIA"
			(at 0 0 -90)
			(layer "F.Fab")
			(hide yes)
			(effects
				(font
					(size 1.27 1.27)
					(thickness 0.15)
				)
			)
		)
		(property "Datasheet" "https://product.samsungsem.com/mlcc/CL10A226MO7JZN.do"
			(at 0 0 -90)
			(layer "F.Fab")
			(hide yes)
			(effects
				(font
					(size 1.27 1.27)
					(thickness 0.15)
				)
			)
		)
		(property "Description" "SMD Multilayer Ceramic Capacitor"
			(at 0 0 -90)
			(layer "F.Fab")
			(hide yes)
			(effects
				(font
					(size 1.27 1.27)
					(thickness 0.15)
				)
			)
		)
		(property "Manufacturer" "Samsung Electro-Mechanics"
			(at 0 0 -90)
			(unlocked yes)
			(layer "F.Fab")
			(hide yes)
			(effects
				(font
					(size 1 1)
					(thickness 0.15)
				)
			)
		)
		(property "MPN" "CL10A226MO7JZNC"
			(at 0 0 -90)
			(unlocked yes)
			(layer "F.Fab")
			(hide yes)
			(effects
				(font
					(size 1 1)
					(thickness 0.15)
				)
			)
		)
		(property "Val" "22u"
			(at 0 0 -90)
			(unlocked yes)
			(layer "F.Fab")
			(hide yes)
			(effects
				(font
					(size 1 1)
					(thickness 0.15)
				)
			)
		)
		(property "License" "Apache-2.0"
			(at 0 0 -90)
			(unlocked yes)
			(layer "F.Fab")
			(hide yes)
			(effects
				(font
					(size 1 1)
					(thickness 0.15)
				)
			)
		)
		(property "Author" "Antmicro"
			(at 0 0 -90)
			(unlocked yes)
			(layer "F.Fab")
			(hide yes)
			(effects
				(font
					(size 1 1)
					(thickness 0.15)
				)
			)
		)
		(property "Voltage" "16V"
			(at 0 0 -90)
			(unlocked yes)
			(layer "F.Fab")
			(hide yes)
			(effects
				(font
					(size 1 1)
					(thickness 0.15)
				)
			)
		)
		(property "Dielectric" ""
			(at 0 0 -90)
			(unlocked yes)
			(layer "F.Fab")
			(hide yes)
			(effects
				(font
					(size 1 1)
					(thickness 0.15)
				)
			)
		)
		(sheetname "Supply")
		(sheetfile "supply.kicad_sch")
		(attr smd)
		(fp_line
			(start -0.15 0.55)
			(end 0.15 0.55)
			(stroke
				(width 0.15)
				(type solid)
			)
			(layer "F.SilkS")
		)
		(fp_line
			(start -0.15 -0.55)
			(end 0.15 -0.55)
			(stroke
				(width 0.15)
				(type solid)
			)
			(layer "F.SilkS")
		)
		(fp_rect
			(start -1.25 -0.65)
			(end 1.25 0.65)
			(stroke
				(width 0.05)
				(type solid)
			)
			(fill none)
			(layer "F.CrtYd")
		)
		(fp_rect
			(start -0.8 -0.45)
			(end 0.8 0.45)
			(stroke
				(width 0.15)
				(type solid)
			)
			(fill none)
			(layer "F.Fab")
		)
		(fp_text user "Author: Antmicro"
			(at -1.682 4.894 -90)
			(layer "F.Fab")
			(hide yes)
			(effects
				(font
					(size 0.7 0.7)
					(thickness 0.15)
				)
				(justify left bottom)
			)
		)
		(fp_text user "License: Apache-2.0"
			(at -1.682 5.895 -90)
			(layer "F.Fab")
			(hide yes)
			(effects
				(font
					(size 0.7 0.7)
					(thickness 0.15)
				)
				(justify left bottom)
			)
		)
		(fp_text user "${REFERENCE}"
			(at -1.682 3.895 -90)
			(layer "F.Fab")
			(hide yes)
			(effects
				(font
					(size 0.7 0.7)
					(thickness 0.15)
				)
				(justify left bottom)
			)
		)
		(pad "1" smd roundrect
			(at -0.7 0 270)
			(size 0.8 1.1)
			(layers "F.Cu" "F.Paste" "F.Mask")
			(roundrect_rratio 0.2)
			(net 1 "GND")
			(pintype "passive")
		)
		(pad "2" smd roundrect
			(at 0.7 0 270)
			(size 0.8 1.1)
			(layers "F.Cu" "F.Paste" "F.Mask")
			(roundrect_rratio 0.2)
			(net 641 "/Supply/3V3_OUT")
			(pintype "passive")
		)
	)
	(footprint "antmicro-footprints:R_0402_1005Metric"
		(layer "F.Cu")
		(at 107.2 110.625 -90)
		(descr "Resistor SMD 0402")
		(tags "resistor SMD 0402")
		(property "Reference" "R126"
			(at 3.625 -0.45 -90)
			(layer "F.SilkS")
			(effects
				(font
					(size 0.7 0.7)
					(thickness 0.15)
				)
				(justify left bottom)
			)
		)
		(property "Value" "R_200k_0402"
			(at 0 1.4 -90)
			(layer "F.Fab")
			(effects
				(font
					(size 0.7 0.7)
					(thickness 0.15)
				)
				(justify left bottom)
			)
		)
		(property "Footprint" "antmicro-footprints:R_0402_1005Metric"
			(at 0 0 -90)
			(layer "F.Fab")
			(hide yes)
			(effects
				(font
					(size 1.27 1.27)
					(thickness 0.15)
				)
			)
		)
		(property "Datasheet" "https://www.bourns.com/docs/product-datasheets/cr.pdf"
			(at 0 0 -90)
			(layer "F.Fab")
			(hide yes)
			(effects
				(font
					(size 1.27 1.27)
					(thickness 0.15)
				)
			)
		)
		(property "Author" "Antmicro"
			(at -3.425 217.825 0)
			(layer "F.Fab")
			(hide yes)
			(effects
				(font
					(size 1 1)
					(thickness 0.15)
				)
			)
		)
		(property "License" "Apache-2.0"
			(at -3.425 217.825 0)
			(layer "F.Fab")
			(hide yes)
			(effects
				(font
					(size 1 1)
					(thickness 0.15)
				)
			)
		)
		(property "MPN" "CR0402-FX-2003GLF"
			(at -3.425 217.825 0)
			(layer "F.Fab")
			(hide yes)
			(effects
				(font
					(size 1 1)
					(thickness 0.15)
				)
			)
		)
		(property "Manufacturer" "Bourns"
			(at -3.425 217.825 0)
			(layer "F.Fab")
			(hide yes)
			(effects
				(font
					(size 1 1)
					(thickness 0.15)
				)
			)
		)
		(property "Tolerance" "1%"
			(at -3.425 217.825 0)
			(layer "F.Fab")
			(hide yes)
			(effects
				(font
					(size 1 1)
					(thickness 0.15)
				)
			)
		)
		(property "Val" "200k"
			(at -3.425 217.825 0)
			(layer "F.Fab")
			(hide yes)
			(effects
				(font
					(size 1 1)
					(thickness 0.15)
				)
			)
		)
		(sheetname "USB3")
		(sheetfile "usb3.kicad_sch")
		(attr smd)
		(fp_rect
			(start -0.925 -0.47)
			(end 0.925 0.47)
			(stroke
				(width 0.05)
				(type default)
			)
			(fill none)
			(layer "F.CrtYd")
		)
		(fp_rect
			(start -0.5 -0.25)
			(end 0.5 0.25)
			(stroke
				(width 0.15)
				(type solid)
			)
			(fill none)
			(layer "F.Fab")
		)
		(fp_text user "${REFERENCE}"
			(at -0.95 3.168 -90)
			(layer "F.Fab")
			(hide yes)
			(effects
				(font
					(size 0.7 0.7)
					(thickness 0.15)
				)
				(justify left bottom)
			)
		)
		(fp_text user "Author: Antmicro"
			(at -0.95 4.169 -90)
			(layer "F.Fab")
			(hide yes)
			(effects
				(font
					(size 0.7 0.7)
					(thickness 0.15)
				)
				(justify left bottom)
			)
		)
		(fp_text user "License: Apache-2.0"
			(at -0.95 5.169 -90)
			(layer "F.Fab")
			(hide yes)
			(effects
				(font
					(size 0.7 0.7)
					(thickness 0.15)
				)
				(justify left bottom)
			)
		)
		(pad "1" smd roundrect
			(at -0.48 0 270)
			(size 0.59 0.64)
			(layers "F.Cu" "F.Paste" "F.Mask")
			(roundrect_rratio 0.25)
			(net 364 "/USB3/USBC1_DIR")
			(pintype "passive")
		)
		(pad "2" smd roundrect
			(at 0.48 0 270)
			(size 0.59 0.64)
			(layers "F.Cu" "F.Paste" "F.Mask")
			(roundrect_rratio 0.25)
			(net 87 "+3V3")
			(pintype "passive")
		)
	)
	(footprint "antmicro-footprints:R_0402_1005Metric"
		(layer "F.Cu")
		(at 96.15 101.4 180)
		(descr "Resistor SMD 0402")
		(tags "resistor SMD 0402")
		(property "Reference" "R162"
			(at -0.8 -0.4 180)
			(layer "F.SilkS")
			(effects
				(font
					(size 0.7 0.7)
					(thickness 0.15)
				)
				(justify left bottom)
			)
		)
		(property "Value" "R_0R_0402"
			(at 0 1.4 180)
			(layer "F.Fab")
			(effects
				(font
					(size 0.7 0.7)
					(thickness 0.15)
				)
				(justify left bottom)
			)
		)
		(property "Footprint" "antmicro-footprints:R_0402_1005Metric"
			(at 0 0 180)
			(layer "F.Fab")
			(hide yes)
			(effects
				(font
					(size 1.27 1.27)
					(thickness 0.15)
				)
			)
		)
		(property "Datasheet" "https://industrial.panasonic.com/cdbs/www-data/pdf/RDA0000/AOA0000C301.pdf"
			(at 0 0 180)
			(layer "F.Fab")
			(hide yes)
			(effects
				(font
					(size 1.27 1.27)
					(thickness 0.15)
				)
			)
		)
		(property "Author" "Antmicro"
			(at 192.3 202.8 0)
			(layer "F.Fab")
			(hide yes)
			(effects
				(font
					(size 1 1)
					(thickness 0.15)
				)
			)
		)
		(property "Current" "1A"
			(at 192.3 202.8 0)
			(layer "F.Fab")
			(hide yes)
			(effects
				(font
					(size 1 1)
					(thickness 0.15)
				)
			)
		)
		(property "License" "Apache-2.0"
			(at 192.3 202.8 0)
			(layer "F.Fab")
			(hide yes)
			(effects
				(font
					(size 1 1)
					(thickness 0.15)
				)
			)
		)
		(property "MPN" "ERJ2GE0R00X"
			(at 192.3 202.8 0)
			(layer "F.Fab")
			(hide yes)
			(effects
				(font
					(size 1 1)
					(thickness 0.15)
				)
			)
		)
		(property "Manufacturer" "Panasonic"
			(at 192.3 202.8 0)
			(layer "F.Fab")
			(hide yes)
			(effects
				(font
					(size 1 1)
					(thickness 0.15)
				)
			)
		)
		(property "Tolerance" ""
			(at 192.3 202.8 0)
			(layer "F.Fab")
			(hide yes)
			(effects
				(font
					(size 1 1)
					(thickness 0.15)
				)
			)
		)
		(property "Val" "0R"
			(at 192.3 202.8 0)
			(layer "F.Fab")
			(hide yes)
			(effects
				(font
					(size 1 1)
					(thickness 0.15)
				)
			)
		)
		(sheetname "CSI")
		(sheetfile "csi.kicad_sch")
		(attr smd)
		(fp_rect
			(start -0.925 -0.47)
			(end 0.925 0.47)
			(stroke
				(width 0.05)
				(type default)
			)
			(fill none)
			(layer "F.CrtYd")
		)
		(fp_rect
			(start -0.5 -0.25)
			(end 0.5 0.25)
			(stroke
				(width 0.15)
				(type solid)
			)
			(fill none)
			(layer "F.Fab")
		)
		(fp_text user "License: Apache-2.0"
			(at -0.95 5.169 180)
			(layer "F.Fab")
			(hide yes)
			(effects
				(font
					(size 0.7 0.7)
					(thickness 0.15)
				)
				(justify left bottom)
			)
		)
		(fp_text user "${REFERENCE}"
			(at -0.95 3.168 180)
			(layer "F.Fab")
			(hide yes)
			(effects
				(font
					(size 0.7 0.7)
					(thickness 0.15)
				)
				(justify left bottom)
			)
		)
		(fp_text user "Author: Antmicro"
			(at -0.95 4.169 180)
			(layer "F.Fab")
			(hide yes)
			(effects
				(font
					(size 0.7 0.7)
					(thickness 0.15)
				)
				(justify left bottom)
			)
		)
		(pad "1" smd roundrect
			(at -0.48 0 180)
			(size 0.59 0.64)
			(layers "F.Cu" "F.Paste" "F.Mask")
			(roundrect_rratio 0.25)
			(net 512 "/CSI/I2C_MUX_SCL")
			(pintype "passive")
		)
		(pad "2" smd roundrect
			(at 0.48 0 180)
			(size 0.59 0.64)
			(layers "F.Cu" "F.Paste" "F.Mask")
			(roundrect_rratio 0.25)
			(net 81 "SCL_CAM")
			(pintype "passive")
		)
	)
)
